# BASEBOARD_FAB2 (Tioga Pass) — schematic netlist excerpt (pin names and nets, part order shuffled) for the footprints in the layout excerpt that follows; sources: Cadence DE-HDL packaged netlist, KiCad conversion of Wiwynn_Tioga_Pass_MB.brd

C1F10  CAP  0.22UF 16V 10% X7R  pkg 0402  page 181 : A = P3E_CPU1_PE3_MP_C_TXN<4> ; B = P3E_CPU1_PE3_MP_TXN<4>
C8C2  CAP  33.0PF 50V 5% COG  pkg 0402LF  page 118 : A = XTAL_KR_25M_OUT ; B = GND
R1T24  RES  0.0 5% EMPTY  pkg 0402  page 147 : A = PUMP_TACH0 ; B = FM_FLASH_DESC_OVERRIDE

(kicad_pcb
	(version 20260206)
	(generator "pcbnew")
	(generator_version "10.0")
	(general
		(thickness 1.6)
		(legacy_teardrops no)
	)
	(paper "A4")
	(title_block
		(title "Wiwynn_Tioga_Pass_MB.brd")
		(comment 1 "Tioga Pass / footprints 441-443 of 4770")
	)
	(layers
		(0 "F.Cu" signal "TOP")
		(4 "In1.Cu" signal "L2GND")
		(6 "In2.Cu" signal "L3")
		(8 "In3.Cu" signal "L4GND")
		(10 "In4.Cu" signal "L5")
		(12 "In5.Cu" signal "L6GND")
		(14 "In6.Cu" signal "L7VCC")
		(16 "In7.Cu" signal "L8VCC")
		(18 "In8.Cu" signal "L9GND")
		(20 "In9.Cu" signal "L10")
		(22 "In10.Cu" signal "L11GND")
		(24 "In11.Cu" signal "L12")
		(26 "In12.Cu" signal "L13GND")
		(2 "B.Cu" signal "BOTTOM")
		(9 "F.Adhes" user "F.Adhesive")
		(11 "B.Adhes" user "B.Adhesive")
		(13 "F.Paste" user "Package Geometry/Pastemask Top")
		(15 "B.Paste" user "Package Geometry/Pastemask Bottom")
		(5 "F.SilkS" user "Ref Des/Silkscreen Top")
		(7 "B.SilkS" user "Ref Des/Silkscreen Bottom")
		(1 "F.Mask" user "Board Geometry/Soldermask Top")
		(3 "B.Mask" user "Board Geometry/Soldermask Bottom")
		(17 "Dwgs.User" user "User.Drawings")
		(19 "Cmts.User" user "User.Comments")
		(21 "Eco1.User" user "User.Eco1")
		(23 "Eco2.User" user "User.Eco2")
		(25 "Edge.Cuts" user "Board Geometry/Outline")
		(27 "Margin" user)
		(31 "F.CrtYd" user "Package Geometry/Place Bound Top")
		(29 "B.CrtYd" user "Package Geometry/Place Bound Bottom")
		(35 "F.Fab" user "Ref Des/Assembly Top")
		(33 "B.Fab" user "Ref Des/Assembly Bottom")
	)
	(footprint ""
		(layer "F.Cu")
		(at 13.8938 -31.242 90)
		(property "Reference" "C1F10"
			(at 0 0 90)
			(layer "F.SilkS")
			(hide yes)
			(effects
				(font
					(size 1.27 1.27)
				)
			)
		)
		(property "Value" ""
			(at 0 0 90)
			(layer "F.Fab")
			(effects
				(font
					(size 1.27 1.27)
				)
			)
		)
		(duplicate_pad_numbers_are_jumpers no)
		(fp_rect
			(start -0.3048 -0.1016)
			(end 0.3048 0.9906)
			(stroke
				(width 0)
				(type default)
			)
			(fill no)
			(layer "F.CrtYd")
		)
		(fp_line
			(start 0.3048 -0.1016)
			(end -0.3048 -0.1016)
			(stroke
				(width 0.1)
				(type default)
			)
			(layer "F.Fab")
		)
		(fp_line
			(start -0.3048 -0.1016)
			(end -0.3048 0.9906)
			(stroke
				(width 0.1)
				(type default)
			)
			(layer "F.Fab")
		)
		(fp_line
			(start 0.3048 0.9906)
			(end 0.3048 -0.1016)
			(stroke
				(width 0.1)
				(type default)
			)
			(layer "F.Fab")
		)
		(fp_line
			(start -0.3048 0.9906)
			(end 0.3048 0.9906)
			(stroke
				(width 0.1)
				(type default)
			)
			(layer "F.Fab")
		)
		(pad "1" smd rect
			(at 0 0 90)
			(size 0.508 0.508)
			(layers "F.Cu" "F.Mask" "F.Paste")
			(net "P3E_CPU1_PE3_MP_C_TXN<4>")
		)
		(pad "2" smd rect
			(at 0 0.889 90)
			(size 0.508 0.508)
			(layers "F.Cu" "F.Mask" "F.Paste")
			(net "P3E_CPU1_PE3_MP_TXN<4>")
		)
		(zone
			(layer "F.Cu")
			(hatch none 0.5)
			(connect_pads
				(clearance 0)
			)
			(min_thickness 0.25)
			(keepout
				(tracks not_allowed)
				(vias allowed)
				(pads allowed)
				(copperpour not_allowed)
				(footprints allowed)
			)
			(placement
				(enabled no)
				(sheetname "")
			)
			(fill
				(thermal_gap 0.5)
				(thermal_bridge_width 0.5)
				(island_removal_mode 0)
			)
			(polygon
				(pts
					(xy 14.1478 -30.988) (xy 14.5288 -30.988) (xy 14.5288 -31.496) (xy 14.1478 -31.496)
				)
			)
		)
		(zone
			(layer "F.Cu")
			(hatch none 0.5)
			(connect_pads
				(clearance 0)
			)
			(min_thickness 0.25)
			(keepout
				(tracks allowed)
				(vias not_allowed)
				(pads allowed)
				(copperpour not_allowed)
				(footprints allowed)
			)
			(placement
				(enabled no)
				(sheetname "")
			)
			(fill
				(thermal_gap 0.5)
				(thermal_bridge_width 0.5)
				(island_removal_mode 0)
			)
			(polygon
				(pts
					(xy 14.1478 -30.988) (xy 14.5288 -30.988) (xy 14.5288 -31.496) (xy 14.1478 -31.496)
				)
			)
		)
	)
	(footprint ""
		(layer "F.Cu")
		(at 430.9491 -26.797)
		(property "Reference" "R1T24"
			(at 0 0 0)
			(layer "F.SilkS")
			(hide yes)
			(effects
				(font
					(size 1.27 1.27)
				)
			)
		)
		(property "Value" ""
			(at 0 0 0)
			(layer "F.Fab")
			(effects
				(font
					(size 1.27 1.27)
				)
			)
		)
		(duplicate_pad_numbers_are_jumpers no)
		(fp_poly
			(pts
				(xy -0.2794 -0.1016) (xy 0.2794 -0.1016) (xy 0.2794 0.9906) (xy -0.2794 0.9906)
			)
			(stroke
				(width 0)
				(type default)
			)
			(fill no)
			(layer "F.CrtYd")
		)
		(fp_line
			(start -0.2794 -0.1016)
			(end -0.2794 0.9906)
			(stroke
				(width 0.1)
				(type default)
			)
			(layer "F.Fab")
		)
		(fp_line
			(start -0.2794 0.9906)
			(end 0.2794 0.9906)
			(stroke
				(width 0.1)
				(type default)
			)
			(layer "F.Fab")
		)
		(fp_line
			(start 0.2794 -0.1016)
			(end -0.2794 -0.1016)
			(stroke
				(width 0.1)
				(type default)
			)
			(layer "F.Fab")
		)
		(fp_line
			(start 0.2794 0.9906)
			(end 0.2794 -0.1016)
			(stroke
				(width 0.1)
				(type default)
			)
			(layer "F.Fab")
		)
		(pad "1" smd rect
			(at 0 0)
			(size 0.508 0.508)
			(layers "F.Cu" "F.Mask" "F.Paste")
			(net "PUMP_TACH0")
		)
		(pad "2" smd rect
			(at 0 0.889)
			(size 0.508 0.508)
			(layers "F.Cu" "F.Mask" "F.Paste")
			(net "FM_FLASH_DESC_OVERRIDE")
		)
		(zone
			(layer "F.Cu")
			(hatch none 0.5)
			(connect_pads
				(clearance 0)
			)
			(min_thickness 0.25)
			(keepout
				(tracks allowed)
				(vias not_allowed)
				(pads allowed)
				(copperpour not_allowed)
				(footprints allowed)
			)
			(placement
				(enabled no)
				(sheetname "")
			)
			(fill
				(thermal_gap 0.5)
				(thermal_bridge_width 0.5)
				(island_removal_mode 0)
			)
			(polygon
				(pts
					(xy 430.6951 -26.543) (xy 431.2031 -26.543) (xy 431.2031 -26.162) (xy 430.6951 -26.162)
				)
			)
		)
		(zone
			(layer "F.Cu")
			(hatch none 0.5)
			(connect_pads
				(clearance 0)
			)
			(min_thickness 0.25)
			(keepout
				(tracks not_allowed)
				(vias allowed)
				(pads allowed)
				(copperpour not_allowed)
				(footprints allowed)
			)
			(placement
				(enabled no)
				(sheetname "")
			)
			(fill
				(thermal_gap 0.5)
				(thermal_bridge_width 0.5)
				(island_removal_mode 0)
			)
			(polygon
				(pts
					(xy 430.6951 -26.162) (xy 431.2031 -26.162) (xy 431.2031 -26.543) (xy 430.6951 -26.543)
				)
			)
		)
	)
	(footprint ""
		(layer "F.Cu")
		(at 404.927054 -98.441764)
		(property "Reference" "C8C2"
			(at 0 0 0)
			(layer "F.SilkS")
			(hide yes)
			(effects
				(font
					(size 1.27 1.27)
				)
			)
		)
		(property "Value" ""
			(at 0 0 0)
			(layer "F.Fab")
			(effects
				(font
					(size 1.27 1.27)
				)
			)
		)
		(duplicate_pad_numbers_are_jumpers no)
		(fp_poly
			(pts
				(xy 0.3048 -0.1016) (xy 0.3048 0.9906) (xy -0.3048 0.9906) (xy -0.3048 -0.1016)
			)
			(stroke
				(width 0)
				(type default)
			)
			(fill no)
			(layer "F.CrtYd")
		)
		(fp_line
			(start -0.3048 -0.1016)
			(end -0.3048 0.9906)
			(stroke
				(width 0.1)
				(type default)
			)
			(layer "F.Fab")
		)
		(fp_line
			(start -0.3048 0.9906)
			(end 0.3048 0.9906)
			(stroke
				(width 0.1)
				(type default)
			)
			(layer "F.Fab")
		)
		(fp_line
			(start 0.3048 -0.1016)
			(end -0.3048 -0.1016)
			(stroke
				(width 0.1)
				(type default)
			)
			(layer "F.Fab")
		)
		(fp_line
			(start 0.3048 0.9906)
			(end 0.3048 -0.1016)
			(stroke
				(width 0.1)
				(type default)
			)
			(layer "F.Fab")
		)
		(pad "1" smd rect
			(at 0 0)
			(size 0.508 0.508)
			(layers "F.Cu" "F.Mask" "F.Paste")
			(net "XTAL_KR_25M_OUT")
		)
		(pad "2" smd rect
			(at 0 0.889)
			(size 0.508 0.508)
			(layers "F.Cu" "F.Mask" "F.Paste")
			(net "GND")
		)
		(zone
			(layer "F.Cu")
			(hatch none 0.5)
			(connect_pads
				(clearance 0)
			)
			(min_thickness 0.25)
			(keepout
				(tracks allowed)
				(vias not_allowed)
				(pads allowed)
				(copperpour not_allowed)
				(footprints allowed)
			)
			(placement
				(enabled no)
				(sheetname "")
			)
			(fill
				(thermal_gap 0.5)
				(thermal_bridge_width 0.5)
				(island_removal_mode 0)
			)
			(polygon
				(pts
					(xy 404.673054 -98.187764) (xy 405.181054 -98.187764) (xy 405.181054 -97.806764) (xy 404.673054 -97.806764)
				)
			)
		)
		(zone
			(layer "F.Cu")
			(hatch none 0.5)
			(connect_pads
				(clearance 0)
			)
			(min_thickness 0.25)
			(keepout
				(tracks not_allowed)
				(vias allowed)
				(pads allowed)
				(copperpour not_allowed)
				(footprints allowed)
			)
			(placement
				(enabled no)
				(sheetname "")
			)
			(fill
				(thermal_gap 0.5)
				(thermal_bridge_width 0.5)
				(island_removal_mode 0)
			)
			(polygon
				(pts
					(xy 404.673054 -97.806764) (xy 405.181054 -97.806764) (xy 405.181054 -98.187764) (xy 404.673054 -98.187764)
				)
			)
		)
	)
)
